(kicad_pcb
	(version 20260206)
	(generator "pcbnew")
	(generator_version "10.0")
	(general
		(thickness 1.6)
		(legacy_teardrops no)
	)
	(paper "A4")
	(title_block
		(title "v2-pdb — ms_pdb_v2.brd")
		(comment 1 "Open CloudServer (Microsoft) / footprints 348-348 of 348")
	)
	(layers
		(0 "F.Cu" signal "TOP")
		(4 "In1.Cu" signal "GND")
		(6 "In2.Cu" signal "IN1")
		(8 "In3.Cu" signal "VCC")
		(10 "In4.Cu" signal "VCC1")
		(12 "In5.Cu" signal "IN2")
		(14 "In6.Cu" signal "GND1")
		(2 "B.Cu" signal "BOTTOM")
		(9 "F.Adhes" user "F.Adhesive")
		(11 "B.Adhes" user "B.Adhesive")
		(13 "F.Paste" user "Package Geometry/Pastemask Top")
		(15 "B.Paste" user "Package Geometry/Pastemask Bottom")
		(5 "F.SilkS" user "Ref Des/Silkscreen Top")
		(7 "B.SilkS" user "Ref Des/Silkscreen Bottom")
		(1 "F.Mask" user "Board Geometry/Soldermask Top")
		(3 "B.Mask" user "Board Geometry/Soldermask Bottom")
		(17 "Dwgs.User" user "User.Drawings")
		(19 "Cmts.User" user "User.Comments")
		(21 "Eco1.User" user "User.Eco1")
		(23 "Eco2.User" user "User.Eco2")
		(25 "Edge.Cuts" user "Board Geometry/Outline")
		(27 "Margin" user)
		(31 "F.CrtYd" user "Package Geometry/Place Bound Top")
		(29 "B.CrtYd" user "Package Geometry/Place Bound Bottom")
		(35 "F.Fab" user "Ref Des/Assembly Top")
		(33 "B.Fab" user "Ref Des/Assembly Bottom")
	)
	(footprint ""
		(layer "B.Cu")
		(at 98.951288 -16.810228)
		(property "Reference" ""
			(at 0 0 0)
			(layer "B.SilkS")
			(hide yes)
			(effects
				(font
					(size 1.27 1.27)
				)
				(justify mirror)
			)
		)
		(property "Value" ""
			(at 0 0 0)
			(layer "B.Fab")
			(effects
				(font
					(size 1.27 1.27)
				)
				(justify mirror)
			)
		)
		(duplicate_pad_numbers_are_jumpers no)
		(fp_poly
			(pts
				(arc
					(start 1.4986 0)
					(mid -1.4986 0)
					(end 1.4986 0)
				)
			)
			(stroke
				(width 0)
				(type default)
			)
			(fill no)
			(layer "B.CrtYd")
		)
		(pad "1" smd circle
			(at 0 0 180)
			(size 0.9906 0.9906)
			(layers "B.Cu" "B.Mask" "B.Paste")
			(net "Net_70")
		)
		(zone
			(layer "B.Cu")
			(hatch none 0.5)
			(connect_pads
				(clearance 0)
			)
			(min_thickness 0.25)
			(keepout
				(tracks not_allowed)
				(vias allowed)
				(pads allowed)
				(copperpour not_allowed)
				(footprints allowed)
			)
			(placement
				(enabled no)
				(sheetname "")
			)
			(fill
				(thermal_gap 0.5)
				(thermal_bridge_width 0.5)
				(island_removal_mode 0)
			)
			(polygon
				(pts
					(arc
						(start 100.576888 -16.810228)
						(mid 97.325688 -16.810228)
						(end 100.576888 -16.810228)
					)
				)
			)
		)
	)
)
